(kicad_pcb
	(version 20260206)
	(generator "pcbnew")
	(generator_version "10.0")
	(general
		(thickness 1.6)
		(legacy_teardrops no)
	)
	(paper "A4")
	(title_block
		(title "fcb — Lightning_FCB_BRD.brd")
		(comment 1 "Lightning (Wiwynn / Facebook NVMe JBOF) / footprints 227-231 of 495")
	)
	(layers
		(0 "F.Cu" signal "TOP")
		(4 "In1.Cu" signal "L2GND")
		(6 "In2.Cu" signal "L3VCC")
		(2 "B.Cu" signal "BOTTOM")
		(9 "F.Adhes" user "F.Adhesive")
		(11 "B.Adhes" user "B.Adhesive")
		(13 "F.Paste" user "Package Geometry/Pastemask Top")
		(15 "B.Paste" user "Package Geometry/Pastemask Bottom")
		(5 "F.SilkS" user "Ref Des/Silkscreen Top")
		(7 "B.SilkS" user "Ref Des/Silkscreen Bottom")
		(1 "F.Mask" user "Board Geometry/Soldermask Top")
		(3 "B.Mask" user "Board Geometry/Soldermask Bottom")
		(17 "Dwgs.User" user "User.Drawings")
		(19 "Cmts.User" user "User.Comments")
		(21 "Eco1.User" user "User.Eco1")
		(23 "Eco2.User" user "User.Eco2")
		(25 "Edge.Cuts" user "Board Geometry/Outline")
		(27 "Margin" user)
		(31 "F.CrtYd" user "Package Geometry/Place Bound Top")
		(29 "B.CrtYd" user "Package Geometry/Place Bound Bottom")
		(35 "F.Fab" user "Ref Des/Assembly Top")
		(33 "B.Fab" user "Ref Des/Assembly Bottom")
	)
	(footprint ""
		(layer "F.Cu")
		(at 29.718 -368.808 90)
		(property "Reference" "PU1"
			(at 0 0 90)
			(layer "F.SilkS")
			(hide yes)
			(effects
				(font
					(size 1.27 1.27)
				)
			)
		)
		(property "Value" "ADM1276-3ACPZ-RL-GP"
			(at -5.3975 -5.0292 90)
			(unlocked yes)
			(layer "F.Fab")
			(hide yes)
			(effects
				(font
					(size 1.016 1.016)
					(thickness 0.1524)
				)
			)
		)
		(property "Device Type" "QFN20-G3D25H32"
			(at -5.3975 -6.5532 90)
			(unlocked yes)
			(layer "F.Fab")
			(hide yes)
			(effects
				(font
					(size 1.016 1.016)
					(thickness 0.1524)
				)
			)
		)
		(duplicate_pad_numbers_are_jumpers no)
		(fp_line
			(start -3.5179 -3.5179)
			(end -2.2479 -3.5179)
			(stroke
				(width 0.1524)
				(type default)
			)
			(layer "F.SilkS")
		)
		(fp_line
			(start -1.3208 -3.302)
			(end -1.3208 -3.81)
			(stroke
				(width 0.1524)
				(type default)
			)
			(layer "F.SilkS")
		)
		(fp_line
			(start -3.5179 -2.2479)
			(end -3.5179 -3.5179)
			(stroke
				(width 0.1524)
				(type default)
			)
			(layer "F.SilkS")
		)
		(fp_line
			(start 3.302 -1.2954)
			(end 4.064 -1.2954)
			(stroke
				(width 0.1524)
				(type default)
			)
			(layer "F.SilkS")
		)
		(fp_line
			(start -4.064 1.2954)
			(end -3.302 1.2954)
			(stroke
				(width 0.1524)
				(type default)
			)
			(layer "F.SilkS")
		)
		(fp_line
			(start -3.5179 2.2479)
			(end -3.5179 3.5179)
			(stroke
				(width 0.1524)
				(type default)
			)
			(layer "F.SilkS")
		)
		(fp_line
			(start 3.5179 3.5179)
			(end 3.5179 2.2479)
			(stroke
				(width 0.1524)
				(type default)
			)
			(layer "F.SilkS")
		)
		(fp_line
			(start 2.2479 3.5179)
			(end 3.5179 3.5179)
			(stroke
				(width 0.1524)
				(type default)
			)
			(layer "F.SilkS")
		)
		(fp_line
			(start -3.5179 3.5179)
			(end -2.2479 3.5179)
			(stroke
				(width 0.1524)
				(type default)
			)
			(layer "F.SilkS")
		)
		(fp_line
			(start 1.2954 3.81)
			(end 1.2954 3.302)
			(stroke
				(width 0.1524)
				(type default)
			)
			(layer "F.SilkS")
		)
		(fp_poly
			(pts
				(xy 2.2479 -3.5179) (xy 3.5179 -2.2479) (xy 3.5179 -3.5179)
			)
			(stroke
				(width 0)
				(type default)
			)
			(fill yes)
			(layer "F.SilkS")
		)
		(fp_rect
			(start -2.5019 2.5019)
			(end 2.5019 -2.5019)
			(stroke
				(width 0)
				(type default)
			)
			(fill no)
			(layer "F.CrtYd")
		)
		(fp_poly
			(pts
				(xy -3.5179 3.5179) (xy -3.5179 -2.49682) (xy -2.5019 -2.49682) (xy -2.5019 2.5019) (xy 2.5019 2.5019)
				(xy 2.5019 -2.5019) (xy -3.5179 -2.5019) (xy -3.5179 -3.5179) (xy 3.5179 -3.5179) (xy 3.5179 3.5179)
			)
			(stroke
				(width 0)
				(type default)
			)
			(fill no)
			(layer "F.CrtYd")
		)
		(fp_rect
			(start -3.5179 3.5179)
			(end 3.5179 -3.5179)
			(stroke
				(width 0)
				(type default)
			)
			(fill no)
			(layer "F.Fab")
		)
		(pad "1" smd rect
			(at 1.299972 -2.4384 90)
			(size 0.4064 1.143)
			(layers "F.Cu" "F.Mask" "F.Paste")
			(net "ADM1276_OV")
		)
		(pad "2" smd rect
			(at 0.649986 -2.4384 90)
			(size 0.4064 1.143)
			(layers "F.Cu" "F.Mask" "F.Paste")
			(net "ADM1276_VCAP")
		)
		(pad "3" smd rect
			(at 0 -2.4384 90)
			(size 0.4064 1.143)
			(layers "F.Cu" "F.Mask" "F.Paste")
			(net "ADM1276_ISET")
		)
		(pad "4" smd rect
			(at -0.649986 -2.4384 90)
			(size 0.4064 1.143)
			(layers "F.Cu" "F.Mask" "F.Paste")
			(net "ADM1276_SS")
		)
		(pad "5" smd rect
			(at -1.299972 -2.4384 90)
			(size 0.4064 1.143)
			(layers "F.Cu" "F.Mask" "F.Paste")
			(net "ADM1276_TIMER")
		)
		(pad "6" smd rect
			(at -2.4384 -1.299972 90)
			(size 1.143 0.4064)
			(layers "F.Cu" "F.Mask" "F.Paste")
			(net "ADM1276_LATCH#")
		)
		(pad "7" smd rect
			(at -2.4384 -0.649986 90)
			(size 1.143 0.4064)
			(layers "F.Cu" "F.Mask" "F.Paste")
			(net "ADM1276_ADR")
		)
		(pad "8" smd rect
			(at -2.4384 0 90)
			(size 1.143 0.4064)
			(layers "F.Cu" "F.Mask" "F.Paste")
			(net "ADM1276_EN")
		)
		(pad "9" smd rect
			(at -2.4384 0.649986 90)
			(size 1.143 0.4064)
			(layers "F.Cu" "F.Mask" "F.Paste")
			(net "ADM1276_GPIO2")
		)
		(pad "10" smd rect
			(at -2.4384 1.299972 90)
			(size 1.143 0.4064)
			(layers "F.Cu" "F.Mask" "F.Paste")
			(net "I2C_C_SDA_ADM1276")
		)
		(pad "11" smd rect
			(at -1.299972 2.4384 90)
			(size 0.4064 1.143)
			(layers "F.Cu" "F.Mask" "F.Paste")
			(net "I2C_C_SCL_ADM1276")
		)
		(pad "12" smd rect
			(at -0.649986 2.4384 90)
			(size 0.4064 1.143)
			(layers "F.Cu" "F.Mask" "F.Paste")
			(net "ADM1276_PWRGD")
		)
		(pad "13" smd rect
			(at 0 2.4384 90)
			(size 0.4064 1.143)
			(layers "F.Cu" "F.Mask" "F.Paste")
			(net "ADM1276_FLB")
		)
		(pad "14" smd rect
			(at 0.649986 2.4384 90)
			(size 0.4064 1.143)
			(layers "F.Cu" "F.Mask" "F.Paste")
			(net "ADM1276_VOUT")
		)
		(pad "15" smd rect
			(at 1.299972 2.4384 90)
			(size 0.4064 1.143)
			(layers "F.Cu" "F.Mask" "F.Paste")
			(net "GND")
		)
		(pad "16" smd rect
			(at 2.4384 1.299972 90)
			(size 1.143 0.4064)
			(layers "F.Cu" "F.Mask" "F.Paste")
			(net "ADM1276_GATE_DRV")
		)
		(pad "17" smd rect
			(at 2.4384 0.649986 90)
			(size 1.143 0.4064)
			(layers "F.Cu" "F.Mask" "F.Paste")
			(net "ADM1276_SENSE-")
		)
		(pad "18" smd rect
			(at 2.4384 0 90)
			(size 1.143 0.4064)
			(layers "F.Cu" "F.Mask" "F.Paste")
			(net "ADM1276_SENSE+")
		)
		(pad "19" smd rect
			(at 2.4384 -0.649986 90)
			(size 1.143 0.4064)
			(layers "F.Cu" "F.Mask" "F.Paste")
			(net "ADM1276_VCC")
		)
		(pad "20" smd rect
			(at 2.4384 -1.299972 90)
			(size 1.143 0.4064)
			(layers "F.Cu" "F.Mask" "F.Paste")
			(net "ADM1276_UV")
		)
		(pad "21" smd rect
			(at 0 0 90)
			(size 3.2512 3.2512)
			(layers "F.Cu" "F.Mask" "F.Paste")
			(net "GND")
		)
	)
	(footprint ""
		(layer "F.Cu")
		(at 10.033 -174.752 90)
		(property "Reference" "U10"
			(at 0 0 90)
			(layer "F.SilkS")
			(hide yes)
			(effects
				(font
					(size 1.27 1.27)
				)
			)
		)
		(property "Value" "74LVC1G32GW-1GP"
			(at -2.3368 -8.6868 90)
			(unlocked yes)
			(layer "F.Fab")
			(hide yes)
			(effects
				(font
					(size 1.016 1.016)
					(thickness 0.1524)
				)
			)
		)
		(property "Device Type" "SC70-5H44"
			(at -2.3114 -10.414 90)
			(unlocked yes)
			(layer "F.Fab")
			(hide yes)
			(effects
				(font
					(size 1.016 1.016)
					(thickness 0.1524)
				)
			)
		)
		(duplicate_pad_numbers_are_jumpers no)
		(fp_line
			(start 1.3843 -1.8034)
			(end 1.3843 -1.1176)
			(stroke
				(width 0.3302)
				(type default)
			)
			(layer "F.SilkS")
		)
		(fp_line
			(start 0.6604 -1.8034)
			(end 1.3843 -1.8034)
			(stroke
				(width 0.3302)
				(type default)
			)
			(layer "F.SilkS")
		)
		(fp_line
			(start 1.27 -1.7018)
			(end 1.27 1.7018)
			(stroke
				(width 0.1524)
				(type default)
			)
			(layer "F.SilkS")
		)
		(fp_line
			(start -1.27 -1.7018)
			(end 1.27 -1.7018)
			(stroke
				(width 0.1524)
				(type default)
			)
			(layer "F.SilkS")
		)
		(fp_line
			(start 1.27 1.7018)
			(end -1.27 1.7018)
			(stroke
				(width 0.1524)
				(type default)
			)
			(layer "F.SilkS")
		)
		(fp_line
			(start -1.27 1.7018)
			(end -1.27 -1.7018)
			(stroke
				(width 0.1524)
				(type default)
			)
			(layer "F.SilkS")
		)
		(fp_rect
			(start -1.524 1.9558)
			(end 1.524 -1.9558)
			(stroke
				(width 0)
				(type default)
			)
			(fill no)
			(layer "F.CrtYd")
		)
		(fp_poly
			(pts
				(xy -1.524 -1.9558) (xy 1.524 -1.9558) (xy 1.524 1.9558) (xy -1.524 1.9558)
			)
			(stroke
				(width 0)
				(type default)
			)
			(fill no)
			(layer "F.Fab")
		)
		(pad "1" smd rect
			(at 0.65024 -0.8255 90)
			(size 0.4064 1.2192)
			(layers "F.Cu" "F.Mask" "F.Paste")
			(net "SEB_PEER_1A_HB")
		)
		(pad "2" smd rect
			(at 0 -0.8255 90)
			(size 0.4064 1.2192)
			(layers "F.Cu" "F.Mask" "F.Paste")
			(net "SEB_PEER_1B_HB")
		)
		(pad "3" smd rect
			(at -0.65024 -0.8255 90)
			(size 0.4064 1.2192)
			(layers "F.Cu" "F.Mask" "F.Paste")
			(net "GND")
		)
		(pad "4" smd rect
			(at -0.65024 0.8255 90)
			(size 0.4064 1.2192)
			(layers "F.Cu" "F.Mask" "F.Paste")
			(net "SEB_PEER_1A_1B_HB_OUT")
		)
		(pad "5" smd rect
			(at 0.65024 0.8255 90)
			(size 0.4064 1.2192)
			(layers "F.Cu" "F.Mask" "F.Paste")
			(net "P3V3")
		)
	)
	(footprint ""
		(layer "F.Cu")
		(at 33.655 -410.591)
		(property "Reference" "PR31"
			(at 0 0 0)
			(layer "F.SilkS")
			(hide yes)
			(effects
				(font
					(size 1.27 1.27)
				)
			)
		)
		(property "Value" "D0005RL1632F-GP-U"
			(at 3.2258 1.2954 0)
			(unlocked yes)
			(layer "F.Fab")
			(hide yes)
			(effects
				(font
					(size 1.016 1.016)
					(thickness 0.1524)
				)
			)
		)
		(property "Device Type" "RL3115-4PH45"
			(at 3.2258 -0.2286 0)
			(unlocked yes)
			(layer "F.Fab")
			(hide yes)
			(effects
				(font
					(size 1.016 1.016)
					(thickness 0.1524)
				)
			)
		)
		(duplicate_pad_numbers_are_jumpers no)
		(fp_line
			(start -2.0574 -1.7653)
			(end -2.0574 -0.4064)
			(stroke
				(width 0.3302)
				(type default)
			)
			(layer "F.SilkS")
		)
		(fp_line
			(start -1.9685 -1.651)
			(end 1.9685 -1.651)
			(stroke
				(width 0.1524)
				(type default)
			)
			(layer "F.SilkS")
		)
		(fp_line
			(start -1.9685 1.651)
			(end -1.9685 -1.651)
			(stroke
				(width 0.1524)
				(type default)
			)
			(layer "F.SilkS")
		)
		(fp_line
			(start -0.5334 -1.7653)
			(end -2.0574 -1.7653)
			(stroke
				(width 0.3302)
				(type default)
			)
			(layer "F.SilkS")
		)
		(fp_line
			(start 1.9685 -1.651)
			(end 1.9685 1.651)
			(stroke
				(width 0.1524)
				(type default)
			)
			(layer "F.SilkS")
		)
		(fp_line
			(start 1.9685 1.651)
			(end -1.9685 1.651)
			(stroke
				(width 0.1524)
				(type default)
			)
			(layer "F.SilkS")
		)
		(fp_poly
			(pts
				(xy -0.561594 -1.726946) (xy -0.053594 -2.234946) (xy -1.069594 -2.234946)
			)
			(stroke
				(width 0)
				(type default)
			)
			(fill yes)
			(layer "F.SilkS")
		)
		(fp_rect
			(start -1.524 0.7493)
			(end 1.524 -0.7493)
			(stroke
				(width 0)
				(type default)
			)
			(fill no)
			(layer "F.CrtYd")
		)
		(fp_poly
			(pts
				(xy -2.2225 1.905) (xy -2.2225 -1.905) (xy 2.2225 -1.905) (xy 2.2225 -0.7493) (xy -1.524 -0.7493)
				(xy -1.524 0.7493) (xy 1.524 0.7493) (xy 1.524 -0.7366) (xy 2.2225 -0.7366) (xy 2.2225 1.905)
			)
			(stroke
				(width 0)
				(type default)
			)
			(fill no)
			(layer "F.CrtYd")
		)
		(fp_rect
			(start -2.2225 1.905)
			(end 2.2225 -1.905)
			(stroke
				(width 0)
				(type default)
			)
			(fill no)
			(layer "F.Fab")
		)
		(pad "1" smd rect
			(at -0.5715 -0.813562)
			(size 2.286 1.143)
			(layers "F.Cu" "F.Mask" "F.Paste")
			(net "P12V_AUX")
		)
		(pad "2" smd rect
			(at -0.5715 0.813562)
			(size 2.286 1.143)
			(layers "F.Cu" "F.Mask" "F.Paste")
			(net "P12V_SENSE_TRACE")
		)
		(pad "3" smd rect
			(at 1.334008 -0.813562)
			(size 0.762 1.143)
			(layers "F.Cu" "F.Mask" "F.Paste")
			(net "SENSE+_R3")
		)
		(pad "4" smd rect
			(at 1.334008 0.813562)
			(size 0.762 1.143)
			(layers "F.Cu" "F.Mask" "F.Paste")
			(net "SENSE-_R3")
		)
		(zone
			(layer "F.Cu")
			(hatch none 0.5)
			(connect_pads
				(clearance 0)
			)
			(min_thickness 0.25)
			(keepout
				(tracks allowed)
				(vias not_allowed)
				(pads allowed)
				(copperpour not_allowed)
				(footprints allowed)
			)
			(placement
				(enabled no)
				(sheetname "")
			)
			(fill
				(thermal_gap 0.5)
				(thermal_bridge_width 0.5)
				(island_removal_mode 0)
			)
			(polygon
				(pts
					(xy 34.2265 -410.833062) (xy 34.608008 -410.833062) (xy 34.608008 -411.3403) (xy 34.2265 -411.3403)
				)
			)
		)
		(zone
			(layer "F.Cu")
			(hatch none 0.5)
			(connect_pads
				(clearance 0)
			)
			(min_thickness 0.25)
			(keepout
				(tracks not_allowed)
				(vias allowed)
				(pads allowed)
				(copperpour not_allowed)
				(footprints allowed)
			)
			(placement
				(enabled no)
				(sheetname "")
			)
			(fill
				(thermal_gap 0.5)
				(thermal_bridge_width 0.5)
				(island_removal_mode 0)
			)
			(polygon
				(pts
					(xy 34.2265 -410.833062) (xy 34.608008 -410.833062) (xy 34.608008 -411.3403) (xy 34.2265 -411.3403)
				)
			)
		)
		(zone
			(layer "F.Cu")
			(hatch none 0.5)
			(connect_pads
				(clearance 0)
			)
			(min_thickness 0.25)
			(keepout
				(tracks allowed)
				(vias not_allowed)
				(pads allowed)
				(copperpour not_allowed)
				(footprints allowed)
			)
			(placement
				(enabled no)
				(sheetname "")
			)
			(fill
				(thermal_gap 0.5)
				(thermal_bridge_width 0.5)
				(island_removal_mode 0)
			)
			(polygon
				(pts
					(xy 34.2265 -409.8417) (xy 34.608008 -409.8417) (xy 34.608008 -410.348938) (xy 34.2265 -410.348938)
				)
			)
		)
		(zone
			(layer "F.Cu")
			(hatch none 0.5)
			(connect_pads
				(clearance 0)
			)
			(min_thickness 0.25)
			(keepout
				(tracks not_allowed)
				(vias allowed)
				(pads allowed)
				(copperpour not_allowed)
				(footprints allowed)
			)
			(placement
				(enabled no)
				(sheetname "")
			)
			(fill
				(thermal_gap 0.5)
				(thermal_bridge_width 0.5)
				(island_removal_mode 0)
			)
			(polygon
				(pts
					(xy 34.2265 -409.8417) (xy 34.608008 -409.8417) (xy 34.608008 -410.348938) (xy 34.2265 -410.348938)
				)
			)
		)
	)
	(footprint ""
		(layer "F.Cu")
		(at 23.368 -369.697 -90)
		(property "Reference" "PC4"
			(at 0 0 270)
			(layer "F.SilkS")
			(hide yes)
			(effects
				(font
					(size 1.27 1.27)
				)
			)
		)
		(property "Value" "SC1U25V3KX-1-GP"
			(at 0 -2.8194 270)
			(unlocked yes)
			(layer "F.Fab")
			(hide yes)
			(effects
				(font
					(size 1.016 1.016)
					(thickness 0.1524)
				)
			)
		)
		(property "Device Type" "C603H36"
			(at 0 -4.3434 270)
			(unlocked yes)
			(layer "F.Fab")
			(hide yes)
			(effects
				(font
					(size 1.016 1.016)
					(thickness 0.1524)
				)
			)
		)
		(duplicate_pad_numbers_are_jumpers no)
		(fp_line
			(start 0.508 0)
			(end -0.508 0)
			(stroke
				(width 0.2032)
				(type default)
			)
			(layer "F.SilkS")
		)
		(fp_rect
			(start -0.5842 1.3335)
			(end 0.5842 -1.3335)
			(stroke
				(width 0)
				(type default)
			)
			(fill no)
			(layer "F.CrtYd")
		)
		(fp_rect
			(start -0.5842 1.3335)
			(end 0.5842 -1.3335)
			(stroke
				(width 0)
				(type default)
			)
			(fill no)
			(layer "F.Fab")
		)
		(pad "1" smd custom
			(at 0 -0.762 270)
			(size 0.2159 0.2159)
			(layers "F.Cu" "F.Mask" "F.Paste")
			(net "ADM1276_VCAP")
			(options
				(clearance outline)
				(anchor circle)
			)
			(primitives
				(gr_poly
					(pts
						(arc
							(start -0.3302 -0.4318)
							(mid -0.402042 -0.402042)
							(end -0.4318 -0.3302)
						)
						(arc
							(start -0.4318 0.3302)
							(mid -0.402042 0.402042)
							(end -0.3302 0.4318)
						)
						(arc
							(start 0.3302 0.4318)
							(mid 0.402042 0.402042)
							(end 0.4318 0.3302)
						)
						(arc
							(start 0.4318 -0.3302)
							(mid 0.402042 -0.402042)
							(end 0.3302 -0.4318)
						)
					)
					(width 0)
					(fill yes)
				)
			)
		)
		(pad "2" smd custom
			(at 0 0.762 270)
			(size 0.2159 0.2159)
			(layers "F.Cu" "F.Mask" "F.Paste")
			(net "GND")
			(options
				(clearance outline)
				(anchor circle)
			)
			(primitives
				(gr_poly
					(pts
						(arc
							(start -0.3302 -0.4318)
							(mid -0.402042 -0.402042)
							(end -0.4318 -0.3302)
						)
						(arc
							(start -0.4318 0.3302)
							(mid -0.402042 0.402042)
							(end -0.3302 0.4318)
						)
						(arc
							(start 0.3302 0.4318)
							(mid 0.402042 0.402042)
							(end 0.4318 0.3302)
						)
						(arc
							(start 0.4318 -0.3302)
							(mid 0.402042 -0.402042)
							(end 0.3302 -0.4318)
						)
					)
					(width 0)
					(fill yes)
				)
			)
		)
	)
	(footprint ""
		(layer "F.Cu")
		(at 34.798 -381 180)
		(property "Reference" "PR24"
			(at 0 0 180)
			(layer "F.SilkS")
			(hide yes)
			(effects
				(font
					(size 1.27 1.27)
				)
			)
		)
		(property "Value" "10R2F-L-GP"
			(at 0.064008 -3.993896 180)
			(unlocked yes)
			(layer "F.Fab")
			(hide yes)
			(effects
				(font
					(size 1.016 1.016)
					(thickness 0.1524)
				)
			)
		)
		(property "Device Type" "R402H14"
			(at 0.064008 -5.517896 180)
			(unlocked yes)
			(layer "F.Fab")
			(hide yes)
			(effects
				(font
					(size 1.016 1.016)
					(thickness 0.1524)
				)
			)
		)
		(duplicate_pad_numbers_are_jumpers no)
		(fp_line
			(start 0.508 -0.9398)
			(end -0.508 -0.9398)
			(stroke
				(width 0.1524)
				(type default)
			)
			(layer "F.SilkS")
		)
		(fp_line
			(start -0.508 -0.9398)
			(end -0.508 0.9398)
			(stroke
				(width 0.1524)
				(type default)
			)
			(layer "F.SilkS")
		)
		(fp_rect
			(start -0.508 0.9398)
			(end 0.508 -0.9398)
			(stroke
				(width 0)
				(type default)
			)
			(fill no)
			(layer "F.CrtYd")
		)
		(fp_rect
			(start -0.508 0.9398)
			(end 0.508 -0.9398)
			(stroke
				(width 0)
				(type default)
			)
			(fill no)
			(layer "F.Fab")
		)
		(pad "1" smd custom
			(at 0 -0.4445 180)
			(size 0.1397 0.1397)
			(layers "F.Cu" "F.Mask" "F.Paste")
			(net "ADM1276_SENSE-")
			(options
				(clearance outline)
				(anchor circle)
			)
			(primitives
				(gr_poly
					(pts
						(arc
							(start -0.1778 -0.2794)
							(mid -0.249642 -0.249642)
							(end -0.2794 -0.1778)
						)
						(arc
							(start -0.2794 0.1778)
							(mid -0.249642 0.249642)
							(end -0.1778 0.2794)
						)
						(arc
							(start 0.1778 0.2794)
							(mid 0.249642 0.249642)
							(end 0.2794 0.1778)
						)
						(arc
							(start 0.2794 -0.1778)
							(mid 0.249642 -0.249642)
							(end 0.1778 -0.2794)
						)
					)
					(width 0)
					(fill yes)
				)
			)
		)
		(pad "2" smd custom
			(at 0 0.4445 180)
			(size 0.1397 0.1397)
			(layers "F.Cu" "F.Mask" "F.Paste")
			(net "SENSE-_R4")
			(options
				(clearance outline)
				(anchor circle)
			)
			(primitives
				(gr_poly
					(pts
						(arc
							(start -0.1778 -0.2794)
							(mid -0.249642 -0.249642)
							(end -0.2794 -0.1778)
						)
						(arc
							(start -0.2794 0.1778)
							(mid -0.249642 0.249642)
							(end -0.1778 0.2794)
						)
						(arc
							(start 0.1778 0.2794)
							(mid 0.249642 0.249642)
							(end 0.2794 0.1778)
						)
						(arc
							(start 0.2794 -0.1778)
							(mid 0.249642 -0.249642)
							(end 0.1778 -0.2794)
						)
					)
					(width 0)
					(fill yes)
				)
			)
		)
	)
)
